# Bryce Canyon_IOM_M2_Stackup.xlsx — Storage_PCB_Test_Note (pcb-stackup)
| 編號(Number) | 內容(Item) | 附加檔案(Files) | 附加說明(Description) |
| 1 | Impedance traceability and test |  | 1、板廠在HVM量產階段採用AQL 0.65 正常檢驗水準二級來抽樣，利用Excel範本(PCB_Vendor_PCB_Number(XXXXX-SA)_Impedance_Report_Template_Date.xlsx)在量產階段(HVM 90天後)，不同lot 的量測結果分開於不同的分頁中，記錄其Min, Max, Mean, Median, Sigma, CP, CK, CPK等數值。 2、阻抗CPK的允收條件為 c= 0 (HVM 90天後)；阻抗數值的允收條件為 ±10%(EVT, DVT, PVT,HVM)。 3、阻抗測試條需擺放於折斷邊上。 |
